(kicad_pcb
	(version 20241229)
	(generator "pcbnew")
	(generator_version "9.0")
	(general
		(thickness 1.63)
		(legacy_teardrops no)
	)
	(paper "A4")
	(title_block
		(title "CM4 Baseboard")
		(date "2026-01-05")
		(rev "1.1.1")
		(company "Antmicro Ltd")
		(comment 1 "www.antmicro.com")
		(comment 9 "footprint 200 of 506 (J202), pads 1-99 of 100")
	)
	(layers
		(0 "F.Cu" signal)
		(4 "In1.Cu" power)
		(6 "In2.Cu" power)
		(8 "In3.Cu" signal)
		(10 "In4.Cu" signal)
		(2 "B.Cu" signal)
		(9 "F.Adhes" user "F.Adhesive")
		(11 "B.Adhes" user "B.Adhesive")
		(13 "F.Paste" user)
		(15 "B.Paste" user)
		(5 "F.SilkS" user "F.Silkscreen")
		(7 "B.SilkS" user "B.Silkscreen")
		(1 "F.Mask" user)
		(3 "B.Mask" user)
		(17 "Dwgs.User" user "User.Drawings")
		(19 "Cmts.User" user "User.Comments")
		(21 "Eco1.User" user "User.Eco1")
		(23 "Eco2.User" user "User.Eco2")
		(25 "Edge.Cuts" user)
		(27 "Margin" user)
		(31 "F.CrtYd" user "F.Courtyard")
		(29 "B.CrtYd" user "B.Courtyard")
		(35 "F.Fab" user)
		(33 "B.Fab" user)
	)
	(footprint "antmicro-footprints:Conn_Socket_Hirose_DF40_2x50_DF40HC-3.0-100DS-0.4V"
		(layer "F.Cu")
		(at 114.020961 154.714 -90)
		(property "Reference" "J202"
			(at -8.7975 2.432999 90)
			(layer "F.SilkS")
			(effects
				(font
					(size 0.7 0.7)
					(thickness 0.15)
				)
				(justify left bottom)
			)
		)
		(property "Value" "Socket_Hirose_DF40_2x50_DF40HC-3.0-100DS-0.4V"
			(at 0 3.25 90)
			(layer "F.Fab")
			(effects
				(font
					(size 0.7 0.7)
					(thickness 0.15)
				)
				(justify left bottom)
			)
		)
		(property "Datasheet" "https://www.hirose.com/en/product/document?clcode=CL0684-4151-0-51&productname=DF40HC(3.0)-100DS-0.4V(51&series=DF40&documenttype=Catalog&lang=en&documentid=en_DF40_CAT"
			(at 0 0 270)
			(layer "F.Fab")
			(hide yes)
			(effects
				(font
					(size 1.27 1.27)
					(thickness 0.15)
				)
			)
		)
		(property "Manufacturer" "Hirose Electric"
			(at 0 0 270)
			(unlocked yes)
			(layer "F.Fab")
			(hide yes)
			(effects
				(font
					(size 1 1)
					(thickness 0.15)
				)
			)
		)
		(property "MPN" "DF40HC(3.0)-100DS-0.4V(51)"
			(at 0 0 270)
			(unlocked yes)
			(layer "F.Fab")
			(hide yes)
			(effects
				(font
					(size 1 1)
					(thickness 0.15)
				)
			)
		)
		(property "Author" "Antmicro"
			(at 0 0 270)
			(unlocked yes)
			(layer "F.Fab")
			(hide yes)
			(effects
				(font
					(size 1 1)
					(thickness 0.15)
				)
			)
		)
		(property "License" "Apache-2.0"
			(at 0 0 270)
			(unlocked yes)
			(layer "F.Fab")
			(hide yes)
			(effects
				(font
					(size 1 1)
					(thickness 0.15)
				)
			)
		)
		(property "Pitch" "0.4 mm"
			(at 0 0 270)
			(unlocked yes)
			(layer "F.Fab")
			(hide yes)
			(effects
				(font
					(size 1 1)
					(thickness 0.15)
				)
			)
		)
		(sheetname "/Compute module/")
		(sheetfile "compute-module.kicad_sch")
		(attr smd)
		(pad "1" smd rect
			(at -9.798 1.547 270)
			(size 0.2 0.7)
			(layers "F.Cu" "F.Mask" "F.Paste")
			(net 279 "/Compute module/USB.OTGID")
			(pintype "passive")
		)
		(pad "2" smd rect
			(at -9.798 -1.534 270)
			(size 0.2 0.7)
			(layers "F.Cu" "F.Mask" "F.Paste")
			(net 144 "/Compute module/NVMe.~{CLK_REQ}")
			(pintype "passive")
		)
		(pad "3" smd rect
			(at -9.398 1.547 270)
			(size 0.2 0.7)
			(layers "F.Cu" "F.Mask" "F.Paste")
			(net 38 "/Compute module/USB.D_N")
			(pintype "passive")
		)
		(pad "4" smd rect
			(at -9.398 -1.534 270)
			(size 0.2 0.7)
			(layers "F.Cu" "F.Mask" "F.Paste")
			(net 174 "unconnected-(J202-Pad4)")
			(pintype "passive+no_connect")
		)
		(pad "5" smd rect
			(at -8.997 1.547 270)
			(size 0.2 0.7)
			(layers "F.Cu" "F.Mask" "F.Paste")
			(net 39 "/Compute module/USB.D_P")
			(pintype "passive")
		)
		(pad "6" smd rect
			(at -8.997 -1.534 270)
			(size 0.2 0.7)
			(layers "F.Cu" "F.Mask" "F.Paste")
			(net 157 "unconnected-(J202-Pad6)")
			(pintype "passive+no_connect")
		)
		(pad "7" smd rect
			(at -8.597 1.547 270)
			(size 0.2 0.7)
			(layers "F.Cu" "F.Mask" "F.Paste")
			(net 3 "GND")
			(pintype "passive")
		)
		(pad "8" smd rect
			(at -8.597 -1.534 270)
			(size 0.2 0.7)
			(layers "F.Cu" "F.Mask" "F.Paste")
			(net 3 "GND")
			(pintype "passive")
		)
		(pad "9" smd rect
			(at -8.196 1.547 270)
			(size 0.2 0.7)
			(layers "F.Cu" "F.Mask" "F.Paste")
			(net 145 "/Compute module/NVMe.~{RST}")
			(pintype "passive")
		)
		(pad "10" smd rect
			(at -8.196 -1.534 270)
			(size 0.2 0.7)
			(layers "F.Cu" "F.Mask" "F.Paste")
			(net 40 "/Compute module/NVMe.CLK_P")
			(pintype "passive")
		)
		(pad "11" smd rect
			(at -7.797 1.547 270)
			(size 0.2 0.7)
			(layers "F.Cu" "F.Mask" "F.Paste")
			(net 256 "/Compute module/VDAC_COMP")
			(pintype "passive")
		)
		(pad "12" smd rect
			(at -7.797 -1.534 270)
			(size 0.2 0.7)
			(layers "F.Cu" "F.Mask" "F.Paste")
			(net 41 "/Compute module/NVMe.CLK_N")
			(pintype "passive")
		)
		(pad "13" smd rect
			(at -7.397 1.547 270)
			(size 0.2 0.7)
			(layers "F.Cu" "F.Mask" "F.Paste")
			(net 3 "GND")
			(pintype "passive")
		)
		(pad "14" smd rect
			(at -7.397 -1.534 270)
			(size 0.2 0.7)
			(layers "F.Cu" "F.Mask" "F.Paste")
			(net 3 "GND")
			(pintype "passive")
		)
		(pad "15" smd rect
			(at -6.997 1.547 270)
			(size 0.2 0.7)
			(layers "F.Cu" "F.Mask" "F.Paste")
			(net 42 "/CSI/CSI1.D0_N")
			(pintype "passive")
		)
		(pad "16" smd rect
			(at -6.997 -1.534 270)
			(size 0.2 0.7)
			(layers "F.Cu" "F.Mask" "F.Paste")
			(net 171 "/Compute module/NVMe.RX0_P")
			(pintype "passive")
		)
		(pad "17" smd rect
			(at -6.596 1.547 270)
			(size 0.2 0.7)
			(layers "F.Cu" "F.Mask" "F.Paste")
			(net 44 "/CSI/CSI1.D0_P")
			(pintype "passive")
		)
		(pad "18" smd rect
			(at -6.596 -1.534 270)
			(size 0.2 0.7)
			(layers "F.Cu" "F.Mask" "F.Paste")
			(net 170 "/Compute module/NVMe.RX0_N")
			(pintype "passive")
		)
		(pad "19" smd rect
			(at -6.197 1.547 270)
			(size 0.2 0.7)
			(layers "F.Cu" "F.Mask" "F.Paste")
			(net 3 "GND")
			(pintype "passive")
		)
		(pad "20" smd rect
			(at -6.197 -1.534 270)
			(size 0.2 0.7)
			(layers "F.Cu" "F.Mask" "F.Paste")
			(net 3 "GND")
			(pintype "passive")
		)
		(pad "21" smd rect
			(at -5.797 1.547 270)
			(size 0.2 0.7)
			(layers "F.Cu" "F.Mask" "F.Paste")
			(net 46 "/CSI/CSI1.D1_N")
			(pintype "passive")
		)
		(pad "22" smd rect
			(at -5.797 -1.534 270)
			(size 0.2 0.7)
			(layers "F.Cu" "F.Mask" "F.Paste")
			(net 173 "/Compute module/NVMe.TX0_P")
			(pintype "passive")
		)
		(pad "23" smd rect
			(at -5.398 1.547 270)
			(size 0.2 0.7)
			(layers "F.Cu" "F.Mask" "F.Paste")
			(net 50 "/CSI/CSI1.D1_P")
			(pintype "passive")
		)
		(pad "24" smd rect
			(at -5.398 -1.534 270)
			(size 0.2 0.7)
			(layers "F.Cu" "F.Mask" "F.Paste")
			(net 172 "/Compute module/NVMe.TX0_N")
			(pintype "passive")
		)
		(pad "25" smd rect
			(at -4.997 1.547 270)
			(size 0.2 0.7)
			(layers "F.Cu" "F.Mask" "F.Paste")
			(net 3 "GND")
			(pintype "passive")
		)
		(pad "26" smd rect
			(at -4.997 -1.534 270)
			(size 0.2 0.7)
			(layers "F.Cu" "F.Mask" "F.Paste")
			(net 3 "GND")
			(pintype "passive")
		)
		(pad "27" smd rect
			(at -4.596 1.547 270)
			(size 0.2 0.7)
			(layers "F.Cu" "F.Mask" "F.Paste")
			(net 52 "/CSI/CSI1.CLK_N")
			(pintype "passive")
		)
		(pad "28" smd rect
			(at -4.596 -1.534 270)
			(size 0.2 0.7)
			(layers "F.Cu" "F.Mask" "F.Paste")
			(net 53 "/CSI/CSI0.D0_N")
			(pintype "passive")
		)
		(pad "29" smd rect
			(at -4.197 1.547 270)
			(size 0.2 0.7)
			(layers "F.Cu" "F.Mask" "F.Paste")
			(net 54 "/CSI/CSI1.CLK_P")
			(pintype "passive")
		)
		(pad "30" smd rect
			(at -4.197 -1.534 270)
			(size 0.2 0.7)
			(layers "F.Cu" "F.Mask" "F.Paste")
			(net 55 "/CSI/CSI0.D0_P")
			(pintype "passive")
		)
		(pad "31" smd rect
			(at -3.795 1.547 270)
			(size 0.2 0.7)
			(layers "F.Cu" "F.Mask" "F.Paste")
			(net 3 "GND")
			(pintype "passive")
		)
		(pad "32" smd rect
			(at -3.795 -1.534 270)
			(size 0.2 0.7)
			(layers "F.Cu" "F.Mask" "F.Paste")
			(net 3 "GND")
			(pintype "passive")
		)
		(pad "33" smd rect
			(at -3.396 1.547 270)
			(size 0.2 0.7)
			(layers "F.Cu" "F.Mask" "F.Paste")
			(net 56 "/CSI/CSI1.D2_N")
			(pintype "passive")
		)
		(pad "34" smd rect
			(at -3.396 -1.534 270)
			(size 0.2 0.7)
			(layers "F.Cu" "F.Mask" "F.Paste")
			(net 57 "/CSI/CSI0.D1_N")
			(pintype "passive")
		)
		(pad "35" smd rect
			(at -2.997 1.547 270)
			(size 0.2 0.7)
			(layers "F.Cu" "F.Mask" "F.Paste")
			(net 58 "/CSI/CSI1.D2_P")
			(pintype "passive")
		)
		(pad "36" smd rect
			(at -2.997 -1.534 270)
			(size 0.2 0.7)
			(layers "F.Cu" "F.Mask" "F.Paste")
			(net 67 "/CSI/CSI0.D1_P")
			(pintype "passive")
		)
		(pad "37" smd rect
			(at -2.598 1.547 270)
			(size 0.2 0.7)
			(layers "F.Cu" "F.Mask" "F.Paste")
			(net 3 "GND")
			(pintype "passive")
		)
		(pad "38" smd rect
			(at -2.598 -1.534 270)
			(size 0.2 0.7)
			(layers "F.Cu" "F.Mask" "F.Paste")
			(net 3 "GND")
			(pintype "passive")
		)
		(pad "39" smd rect
			(at -2.198 1.547 270)
			(size 0.2 0.7)
			(layers "F.Cu" "F.Mask" "F.Paste")
			(net 68 "/CSI/CSI1.D3_N")
			(pintype "passive")
		)
		(pad "40" smd rect
			(at -2.198 -1.534 270)
			(size 0.2 0.7)
			(layers "F.Cu" "F.Mask" "F.Paste")
			(net 69 "/CSI/CSI0.CLK_N")
			(pintype "passive")
		)
		(pad "41" smd rect
			(at -1.798 1.547 270)
			(size 0.2 0.7)
			(layers "F.Cu" "F.Mask" "F.Paste")
			(net 70 "/CSI/CSI1.D3_P")
			(pintype "passive")
		)
		(pad "42" smd rect
			(at -1.798 -1.534 270)
			(size 0.2 0.7)
			(layers "F.Cu" "F.Mask" "F.Paste")
			(net 71 "/CSI/CSI0.CLK_P")
			(pintype "passive")
		)
		(pad "43" smd rect
			(at -1.396 1.547 270)
			(size 0.2 0.7)
			(layers "F.Cu" "F.Mask" "F.Paste")
			(net 257 "/Compute module/Pf_5V.HPD")
			(pintype "passive")
		)
		(pad "44" smd rect
			(at -1.396 -1.534 270)
			(size 0.2 0.7)
			(layers "F.Cu" "F.Mask" "F.Paste")
			(net 3 "GND")
			(pintype "passive")
		)
		(pad "45" smd rect
			(at -0.997 1.547 270)
			(size 0.2 0.7)
			(layers "F.Cu" "F.Mask" "F.Paste")
			(net 258 "/Compute module/Pf_5V.SDA")
			(pintype "passive")
		)
		(pad "46" smd rect
			(at -0.997 -1.534 270)
			(size 0.2 0.7)
			(layers "F.Cu" "F.Mask" "F.Paste")
			(net 139 "/Compute module/T1_P")
			(pintype "passive")
		)
		(pad "47" smd rect
			(at -0.597 1.547 270)
			(size 0.2 0.7)
			(layers "F.Cu" "F.Mask" "F.Paste")
			(net 259 "/Compute module/Pf_5V.SCL")
			(pintype "passive")
		)
		(pad "48" smd rect
			(at -0.597 -1.534 270)
			(size 0.2 0.7)
			(layers "F.Cu" "F.Mask" "F.Paste")
			(net 146 "/Compute module/T1_N")
			(pintype "passive")
		)
		(pad "49" smd rect
			(at -0.198 1.547 270)
			(size 0.2 0.7)
			(layers "F.Cu" "F.Mask" "F.Paste")
			(net 260 "/Compute module/Pf_5V.CEC")
			(pintype "passive")
		)
		(pad "50" smd rect
			(at -0.198 -1.534 270)
			(size 0.2 0.7)
			(layers "F.Cu" "F.Mask" "F.Paste")
			(net 3 "GND")
			(pintype "passive")
		)
		(pad "51" smd rect
			(at 0.203 1.547 270)
			(size 0.2 0.7)
			(layers "F.Cu" "F.Mask" "F.Paste")
			(net 261 "/Compute module/HDMI.CEC")
			(pintype "passive")
		)
		(pad "52" smd rect
			(at 0.203 -1.534 270)
			(size 0.2 0.7)
			(layers "F.Cu" "F.Mask" "F.Paste")
			(net 147 "/Compute module/R1_P")
			(pintype "passive")
		)
		(pad "53" smd rect
			(at 0.602 1.547 270)
			(size 0.2 0.7)
			(layers "F.Cu" "F.Mask" "F.Paste")
			(net 262 "/Compute module/HDMI.HPD")
			(pintype "passive")
		)
		(pad "54" smd rect
			(at 0.602 -1.534 270)
			(size 0.2 0.7)
			(layers "F.Cu" "F.Mask" "F.Paste")
			(net 148 "/Compute module/R1_N")
			(pintype "passive")
		)
		(pad "55" smd rect
			(at 1.002 1.547 270)
			(size 0.2 0.7)
			(layers "F.Cu" "F.Mask" "F.Paste")
			(net 3 "GND")
			(pintype "passive")
		)
		(pad "56" smd rect
			(at 1.002 -1.534 270)
			(size 0.2 0.7)
			(layers "F.Cu" "F.Mask" "F.Paste")
			(net 3 "GND")
			(pintype "passive")
		)
		(pad "57" smd rect
			(at 1.401 1.547 270)
			(size 0.2 0.7)
			(layers "F.Cu" "F.Mask" "F.Paste")
			(net 149 "/Compute module/R2_N")
			(pintype "passive")
		)
		(pad "58" smd rect
			(at 1.401 -1.534 270)
			(size 0.2 0.7)
			(layers "F.Cu" "F.Mask" "F.Paste")
			(net 150 "/Compute module/T2_P")
			(pintype "passive")
		)
		(pad "59" smd rect
			(at 1.803 1.547 270)
			(size 0.2 0.7)
			(layers "F.Cu" "F.Mask" "F.Paste")
			(net 151 "/Compute module/R2_P")
			(pintype "passive")
		)
		(pad "60" smd rect
			(at 1.803 -1.534 270)
			(size 0.2 0.7)
			(layers "F.Cu" "F.Mask" "F.Paste")
			(net 152 "/Compute module/T2_N")
			(pintype "passive")
		)
		(pad "61" smd rect
			(at 2.203 1.547 270)
			(size 0.2 0.7)
			(layers "F.Cu" "F.Mask" "F.Paste")
			(net 3 "GND")
			(pintype "passive")
		)
		(pad "62" smd rect
			(at 2.203 -1.534 270)
			(size 0.2 0.7)
			(layers "F.Cu" "F.Mask" "F.Paste")
			(net 3 "GND")
			(pintype "passive")
		)
		(pad "63" smd rect
			(at 2.603 1.547 270)
			(size 0.2 0.7)
			(layers "F.Cu" "F.Mask" "F.Paste")
			(net 153 "/Compute module/T3_N")
			(pintype "passive")
		)
		(pad "64" smd rect
			(at 2.603 -1.534 270)
			(size 0.2 0.7)
			(layers "F.Cu" "F.Mask" "F.Paste")
			(net 154 "/Compute module/R3_P")
			(pintype "passive")
		)
		(pad "65" smd rect
			(at 3.002 1.547 270)
			(size 0.2 0.7)
			(layers "F.Cu" "F.Mask" "F.Paste")
			(net 155 "/Compute module/T3_P")
			(pintype "passive")
		)
		(pad "66" smd rect
			(at 3.002 -1.534 270)
			(size 0.2 0.7)
			(layers "F.Cu" "F.Mask" "F.Paste")
			(net 156 "/Compute module/R3_N")
			(pintype "passive")
		)
		(pad "67" smd rect
			(at 3.402 1.547 270)
			(size 0.2 0.7)
			(layers "F.Cu" "F.Mask" "F.Paste")
			(net 3 "GND")
			(pintype "passive")
		)
		(pad "68" smd rect
			(at 3.402 -1.534 270)
			(size 0.2 0.7)
			(layers "F.Cu" "F.Mask" "F.Paste")
			(net 3 "GND")
			(pintype "passive")
		)
		(pad "69" smd rect
			(at 3.802 1.547 270)
			(size 0.2 0.7)
			(layers "F.Cu" "F.Mask" "F.Paste")
			(net 264 "/Compute module/DSI0_C_N")
			(pintype "passive+no_connect")
		)
		(pad "70" smd rect
			(at 3.802 -1.534 270)
			(size 0.2 0.7)
			(layers "F.Cu" "F.Mask" "F.Paste")
			(net 16 "/Compute module/HDMI.D2_P")
			(pintype "passive")
		)
		(pad "71" smd rect
			(at 4.203 1.547 270)
			(size 0.2 0.7)
			(layers "F.Cu" "F.Mask" "F.Paste")
			(net 265 "/Compute module/DSI0_C_P")
			(pintype "passive+no_connect")
		)
		(pad "72" smd rect
			(at 4.203 -1.534 270)
			(size 0.2 0.7)
			(layers "F.Cu" "F.Mask" "F.Paste")
			(net 15 "/Compute module/HDMI.D2_N")
			(pintype "passive")
		)
		(pad "73" smd rect
			(at 4.602 1.547 270)
			(size 0.2 0.7)
			(layers "F.Cu" "F.Mask" "F.Paste")
			(net 3 "GND")
			(pintype "passive")
		)
		(pad "74" smd rect
			(at 4.602 -1.534 270)
			(size 0.2 0.7)
			(layers "F.Cu" "F.Mask" "F.Paste")
			(net 3 "GND")
			(pintype "passive")
		)
		(pad "75" smd rect
			(at 5.002 1.547 270)
			(size 0.2 0.7)
			(layers "F.Cu" "F.Mask" "F.Paste")
			(net 72 "/Compute module/DSI.D0_N")
			(pintype "passive")
		)
		(pad "76" smd rect
			(at 5.002 -1.534 270)
			(size 0.2 0.7)
			(layers "F.Cu" "F.Mask" "F.Paste")
			(net 14 "/Compute module/HDMI.D1_P")
			(pintype "passive")
		)
		(pad "77" smd rect
			(at 5.403 1.547 270)
			(size 0.2 0.7)
			(layers "F.Cu" "F.Mask" "F.Paste")
			(net 73 "/Compute module/DSI.D0_P")
			(pintype "passive")
		)
		(pad "78" smd rect
			(at 5.403 -1.534 270)
			(size 0.2 0.7)
			(layers "F.Cu" "F.Mask" "F.Paste")
			(net 13 "/Compute module/HDMI.D1_N")
			(pintype "passive")
		)
		(pad "79" smd rect
			(at 5.802 1.547 270)
			(size 0.2 0.7)
			(layers "F.Cu" "F.Mask" "F.Paste")
			(net 3 "GND")
			(pintype "passive")
		)
		(pad "80" smd rect
			(at 5.802 -1.534 270)
			(size 0.2 0.7)
			(layers "F.Cu" "F.Mask" "F.Paste")
			(net 3 "GND")
			(pintype "passive")
		)
		(pad "81" smd rect
			(at 6.203 1.547 270)
			(size 0.2 0.7)
			(layers "F.Cu" "F.Mask" "F.Paste")
			(net 74 "/Compute module/DSI.D1_N")
			(pintype "passive")
		)
		(pad "82" smd rect
			(at 6.203 -1.534 270)
			(size 0.2 0.7)
			(layers "F.Cu" "F.Mask" "F.Paste")
			(net 35 "/Compute module/HDMI.D0_P")
			(pintype "passive")
		)
		(pad "83" smd rect
			(at 6.602 1.547 270)
			(size 0.2 0.7)
			(layers "F.Cu" "F.Mask" "F.Paste")
			(net 75 "/Compute module/DSI.D1_P")
			(pintype "passive")
		)
		(pad "84" smd rect
			(at 6.602 -1.534 270)
			(size 0.2 0.7)
			(layers "F.Cu" "F.Mask" "F.Paste")
			(net 34 "/Compute module/HDMI.D0_N")
			(pintype "passive")
		)
		(pad "85" smd rect
			(at 7.001 1.547 270)
			(size 0.2 0.7)
			(layers "F.Cu" "F.Mask" "F.Paste")
			(net 3 "GND")
			(pintype "passive")
		)
		(pad "86" smd rect
			(at 7.001 -1.534 270)
			(size 0.2 0.7)
			(layers "F.Cu" "F.Mask" "F.Paste")
			(net 3 "GND")
			(pintype "passive")
		)
		(pad "87" smd rect
			(at 7.403 1.547 270)
			(size 0.2 0.7)
			(layers "F.Cu" "F.Mask" "F.Paste")
			(net 76 "/Compute module/DSI.CLK_N")
			(pintype "passive")
		)
		(pad "88" smd rect
			(at 7.403 -1.534 270)
			(size 0.2 0.7)
			(layers "F.Cu" "F.Mask" "F.Paste")
			(net 25 "/Compute module/HDMI.CLK_P")
			(pintype "passive")
		)
		(pad "89" smd rect
			(at 7.802 1.547 270)
			(size 0.2 0.7)
			(layers "F.Cu" "F.Mask" "F.Paste")
			(net 86 "/Compute module/DSI.CLK_P")
			(pintype "passive")
		)
		(pad "90" smd rect
			(at 7.802 -1.534 270)
			(size 0.2 0.7)
			(layers "F.Cu" "F.Mask" "F.Paste")
			(net 23 "/Compute module/HDMI.CLK_N")
			(pintype "passive")
		)
		(pad "91" smd rect
			(at 8.202 1.547 270)
			(size 0.2 0.7)
			(layers "F.Cu" "F.Mask" "F.Paste")
			(net 3 "GND")
			(pintype "passive")
		)
		(pad "92" smd rect
			(at 8.202 -1.534 270)
			(size 0.2 0.7)
			(layers "F.Cu" "F.Mask" "F.Paste")
			(net 3 "GND")
			(pintype "passive")
		)
		(pad "93" smd rect
			(at 8.602 1.547 270)
			(size 0.2 0.7)
			(layers "F.Cu" "F.Mask" "F.Paste")
			(net 87 "/Compute module/DSI.D2_N")
			(pintype "passive")
		)
		(pad "94" smd rect
			(at 8.602 -1.534 270)
			(size 0.2 0.7)
			(layers "F.Cu" "F.Mask" "F.Paste")
			(net 96 "/Compute module/DSI.D3_N")
			(pintype "passive")
		)
		(pad "95" smd rect
			(at 9.002 1.547 270)
			(size 0.2 0.7)
			(layers "F.Cu" "F.Mask" "F.Paste")
			(net 97 "/Compute module/DSI.D2_P")
			(pintype "passive")
		)
		(pad "96" smd rect
			(at 9.002 -1.534 270)
			(size 0.2 0.7)
			(layers "F.Cu" "F.Mask" "F.Paste")
			(net 98 "/Compute module/DSI.D3_P")
			(pintype "passive")
		)
		(pad "97" smd rect
			(at 9.403 1.547 270)
			(size 0.2 0.7)
			(layers "F.Cu" "F.Mask" "F.Paste")
			(net 3 "GND")
			(pintype "passive")
		)
		(pad "98" smd rect
			(at 9.403 -1.534 270)
			(size 0.2 0.7)
			(layers "F.Cu" "F.Mask" "F.Paste")
			(net 3 "GND")
			(pintype "passive")
		)
		(pad "99" smd rect
			(at 9.803 1.547 270)
			(size 0.2 0.7)
			(layers "F.Cu" "F.Mask" "F.Paste")
			(net 266 "/Compute module/HDMI.SDA")
			(pintype "passive")
		)
	)
)
